(kicad_pcb
	(version 20260206)
	(generator "pcbnew")
	(generator_version "10.0")
	(general
		(thickness 1.6)
		(legacy_teardrops no)
	)
	(paper "A4")
	(title_block
		(title "v1-pdb — T6M_PDB_D_0927_0900.brd")
		(comment 1 "Open CloudServer (Microsoft) / footprints 180-187 of 321")
	)
	(layers
		(0 "F.Cu" signal "TOP")
		(4 "In1.Cu" signal "GND")
		(6 "In2.Cu" signal "IN1")
		(8 "In3.Cu" signal "VCC")
		(10 "In4.Cu" signal "VCC1")
		(12 "In5.Cu" signal "IN2")
		(14 "In6.Cu" signal "GND1")
		(2 "B.Cu" signal "BOTTOM")
		(9 "F.Adhes" user "F.Adhesive")
		(11 "B.Adhes" user "B.Adhesive")
		(13 "F.Paste" user "Package Geometry/Pastemask Top")
		(15 "B.Paste" user "Package Geometry/Pastemask Bottom")
		(5 "F.SilkS" user "Ref Des/Silkscreen Top")
		(7 "B.SilkS" user "Ref Des/Silkscreen Bottom")
		(1 "F.Mask" user "Board Geometry/Soldermask Top")
		(3 "B.Mask" user "Board Geometry/Soldermask Bottom")
		(17 "Dwgs.User" user "User.Drawings")
		(19 "Cmts.User" user "User.Comments")
		(21 "Eco1.User" user "User.Eco1")
		(23 "Eco2.User" user "User.Eco2")
		(25 "Edge.Cuts" user "Board Geometry/Outline")
		(27 "Margin" user)
		(31 "F.CrtYd" user "Package Geometry/Place Bound Top")
		(29 "B.CrtYd" user "Package Geometry/Place Bound Bottom")
		(35 "F.Fab" user "Ref Des/Assembly Top")
		(33 "B.Fab" user "Ref Des/Assembly Bottom")
	)
	(footprint ""
		(layer "F.Cu")
		(at 50.32756 -285.205424 180)
		(property "Reference" "CE13"
			(at -4.667758 1.872742 0)
			(unlocked yes)
			(layer "F.SilkS")
			(effects
				(font
					(size 0.7874 0.5842)
					(thickness 0.1524)
				)
				(justify left)
			)
		)
		(property "Value" ""
			(at 0 0 180)
			(layer "F.Fab")
			(effects
				(font
					(size 1.27 1.27)
				)
			)
		)
		(duplicate_pad_numbers_are_jumpers no)
		(fp_line
			(start 0 -4.2672)
			(end 0 4.2672)
			(stroke
				(width 0.1524)
				(type default)
			)
			(layer "F.SilkS")
		)
		(fp_circle
			(center 0 0)
			(end -4.2672 0)
			(stroke
				(width 0.1524)
				(type default)
			)
			(fill no)
			(layer "F.SilkS")
		)
		(fp_poly
			(pts
				(arc
					(start 0 -4.2672)
					(mid 4.2672 0)
					(end 0 4.2672)
				)
			)
			(stroke
				(width 0)
				(type default)
			)
			(fill yes)
			(layer "F.SilkS")
		)
		(fp_poly
			(pts
				(xy -2.5146 -0.762) (xy -0.9906 -0.762) (xy -0.9906 0.762) (xy -2.5146 0.762)
			)
			(stroke
				(width 0)
				(type default)
			)
			(fill no)
			(layer "B.CrtYd")
		)
		(fp_poly
			(pts
				(arc
					(start 1.7526 0.762)
					(mid 2.291415 -0.538815)
					(end 0.9906 0)
				)
				(arc
					(start 0.9906 0.0254)
					(mid 1.206345 0.546255)
					(end 1.7272 0.762)
				)
			)
			(stroke
				(width 0)
				(type default)
			)
			(fill no)
			(layer "B.CrtYd")
		)
		(fp_poly
			(pts
				(arc
					(start -4.2672 0)
					(mid 4.2672 0)
					(end -4.2672 0)
				)
			)
			(stroke
				(width 0)
				(type default)
			)
			(fill no)
			(layer "F.CrtYd")
		)
		(fp_circle
			(center 0 0)
			(end -4.2672 0)
			(stroke
				(width 0.1)
				(type default)
			)
			(fill no)
			(layer "F.Fab")
		)
		(fp_text user "+"
			(at -5.6642 0.15367 180)
			(unlocked yes)
			(layer "F.SilkS")
			(effects
				(font
					(size 0.7874 0.5842)
					(thickness 0.1524)
				)
				(justify left)
			)
		)
		(fp_text user "+"
			(at -5.6642 -0.34925 180)
			(unlocked yes)
			(layer "F.Fab")
			(effects
				(font
					(size 1.905 1.4224)
					(thickness 0.000001)
				)
				(justify left)
			)
		)
		(pad "1" thru_hole rect
			(at -1.75006 0 180)
			(size 1.397 1.397)
			(drill 0.9144)
			(layers "*.Cu" "*.Mask")
			(remove_unused_layers no)
			(net "P12V")
			(clearance 0.0127)
			(thermal_gap 0.0127)
			(padstack
				(mode front_inner_back)
				(layer "Inner"
					(shape circle)
					(size 1.397 1.397)
					(clearance 0.0127)
				)
				(layer "B.Cu"
					(shape rect)
					(size 1.397 1.397)
					(clearance 0.0127)
				)
			)
		)
		(pad "2" thru_hole circle
			(at 1.75006 0 180)
			(size 1.397 1.397)
			(drill 0.9144)
			(layers "*.Cu" "*.Mask")
			(remove_unused_layers no)
			(net "GND")
			(clearance 0.0127)
			(thermal_gap 0.0127)
		)
	)
	(footprint ""
		(layer "F.Cu")
		(at 70.260718 -60.163456 -90)
		(property "Reference" "C9"
			(at -2.559304 0.19939 90)
			(unlocked yes)
			(layer "F.SilkS")
			(effects
				(font
					(size 0.7874 0.5842)
					(thickness 0.1524)
				)
				(justify left)
			)
		)
		(property "Value" ""
			(at 0 0 270)
			(layer "F.Fab")
			(effects
				(font
					(size 1.27 1.27)
				)
			)
		)
		(duplicate_pad_numbers_are_jumpers no)
		(fp_line
			(start -0.7874 0.4064)
			(end -0.7874 -0.4064)
			(stroke
				(width 0.1524)
				(type default)
			)
			(layer "F.SilkS")
		)
		(fp_line
			(start 0.7874 0.4064)
			(end -0.7874 0.4064)
			(stroke
				(width 0.1524)
				(type default)
			)
			(layer "F.SilkS")
		)
		(fp_line
			(start 0 0.381)
			(end 0 -0.381)
			(stroke
				(width 0.1524)
				(type default)
			)
			(layer "F.SilkS")
		)
		(fp_line
			(start -0.7874 -0.4064)
			(end 0.7874 -0.4064)
			(stroke
				(width 0.1524)
				(type default)
			)
			(layer "F.SilkS")
		)
		(fp_line
			(start 0.7874 -0.4064)
			(end 0.7874 0.4064)
			(stroke
				(width 0.1524)
				(type default)
			)
			(layer "F.SilkS")
		)
		(fp_poly
			(pts
				(xy -0.5334 0.254) (xy -0.635 0.254) (xy -0.635 0.2286) (xy -0.635 -0.254) (xy -0.5334 -0.254) (xy -0.5334 -0.2794)
				(xy 0.5334 -0.2794) (xy 0.5334 -0.254) (xy 0.635 -0.254) (xy 0.635 0.254) (xy 0.5334 0.254) (xy 0.5334 0.2794)
				(xy -0.508 0.2794) (xy -0.5334 0.2794)
			)
			(stroke
				(width 0)
				(type default)
			)
			(fill no)
			(layer "F.CrtYd")
		)
		(pad "1" smd rect
			(at 0.40005 0 270)
			(size 0.4572 0.508)
			(layers "F.Cu" "F.Mask" "F.Paste")
			(net "P12V")
		)
		(pad "2" smd rect
			(at -0.40005 0 270)
			(size 0.4572 0.508)
			(layers "F.Cu" "F.Mask" "F.Paste")
			(net "GND")
		)
	)
	(footprint ""
		(layer "F.Cu")
		(at 77.999844 -210.09991)
		(property "Reference" "H7"
			(at -2.377186 -8.725154 0)
			(unlocked yes)
			(layer "F.SilkS")
			(effects
				(font
					(size 0.7874 0.5842)
					(thickness 0.1524)
				)
				(justify left)
			)
		)
		(property "Value" ""
			(at 0 0 0)
			(layer "F.Fab")
			(effects
				(font
					(size 1.27 1.27)
				)
			)
		)
		(duplicate_pad_numbers_are_jumpers no)
		(fp_circle
			(center 0 0)
			(end 7.999984 0)
			(stroke
				(width 0.1524)
				(type default)
			)
			(fill no)
			(layer "F.SilkS")
		)
		(fp_circle
			(center 0 0)
			(end 14.7066 0)
			(stroke
				(width 0.1524)
				(type default)
			)
			(fill no)
			(layer "B.SilkS")
		)
		(fp_poly
			(pts
				(arc
					(start 5.0038 0)
					(mid -5.0038 0)
					(end 5.0038 0)
				)
			)
			(stroke
				(width 0)
				(type default)
			)
			(fill no)
			(layer "F.CrtYd")
		)
		(pad "" np_thru_hole circle
			(at 0 0)
			(size 4.0132 4.0132)
			(drill 4.0132)
			(layers "*.Cu" "*.Mask")
			(clearance 0.381)
			(thermal_gap 0.381)
		)
		(pad "2" thru_hole circle
			(at 0 -3.50012)
			(size 0.762 0.762)
			(drill 0.5588)
			(layers "*.Cu" "*.Mask")
			(remove_unused_layers no)
			(net "GND")
			(clearance 0.1524)
			(thermal_gap 0.1524)
		)
		(pad "3" thru_hole circle
			(at -2.500122 -2.500122)
			(size 0.762 0.762)
			(drill 0.5588)
			(layers "*.Cu" "*.Mask")
			(remove_unused_layers no)
			(net "GND")
			(clearance 0.1524)
			(thermal_gap 0.1524)
		)
		(pad "4" thru_hole circle
			(at -3.50012 0)
			(size 0.762 0.762)
			(drill 0.5588)
			(layers "*.Cu" "*.Mask")
			(remove_unused_layers no)
			(net "GND")
			(clearance 0.1524)
			(thermal_gap 0.1524)
		)
		(pad "5" thru_hole circle
			(at -2.500122 2.500122)
			(size 0.762 0.762)
			(drill 0.5588)
			(layers "*.Cu" "*.Mask")
			(remove_unused_layers no)
			(net "GND")
			(clearance 0.1524)
			(thermal_gap 0.1524)
		)
		(pad "6" thru_hole circle
			(at 0 3.50012)
			(size 0.762 0.762)
			(drill 0.5588)
			(layers "*.Cu" "*.Mask")
			(remove_unused_layers no)
			(net "GND")
			(clearance 0.1524)
			(thermal_gap 0.1524)
		)
		(pad "7" thru_hole circle
			(at 2.500122 2.500122)
			(size 0.762 0.762)
			(drill 0.5588)
			(layers "*.Cu" "*.Mask")
			(remove_unused_layers no)
			(net "GND")
			(clearance 0.1524)
			(thermal_gap 0.1524)
		)
		(pad "8" thru_hole circle
			(at 3.50012 0)
			(size 0.762 0.762)
			(drill 0.5588)
			(layers "*.Cu" "*.Mask")
			(remove_unused_layers no)
			(net "GND")
			(clearance 0.1524)
			(thermal_gap 0.1524)
		)
		(pad "9" thru_hole circle
			(at 2.500122 -2.500122)
			(size 0.762 0.762)
			(drill 0.5588)
			(layers "*.Cu" "*.Mask")
			(remove_unused_layers no)
			(net "GND")
			(clearance 0.1524)
			(thermal_gap 0.1524)
		)
		(zone
			(layer "F.Cu")
			(hatch none 0.5)
			(connect_pads
				(clearance 0)
			)
			(min_thickness 0.25)
			(keepout
				(tracks not_allowed)
				(vias allowed)
				(pads allowed)
				(copperpour not_allowed)
				(footprints allowed)
			)
			(placement
				(enabled no)
				(sheetname "")
			)
			(fill
				(thermal_gap 0.5)
				(thermal_bridge_width 0.5)
				(island_removal_mode 0)
			)
			(polygon
				(pts
					(arc
						(start 77.999844 -218.10091)
						(mid 69.998844 -210.09991)
						(end 77.999844 -202.09891)
					)
					(arc
						(start 77.999844 -202.09891)
						(mid 79.434944 -203.53401)
						(end 77.999844 -204.96911)
					)
					(arc
						(start 77.999844 -204.96911)
						(mid 72.869044 -210.09991)
						(end 77.999844 -215.23071)
					)
					(arc
						(start 77.999844 -215.23071)
						(mid 79.434944 -216.66581)
						(end 77.999844 -218.10091)
					)
				)
			)
		)
		(zone
			(layer "F.Cu")
			(hatch none 0.5)
			(connect_pads
				(clearance 0)
			)
			(min_thickness 0.25)
			(keepout
				(tracks not_allowed)
				(vias allowed)
				(pads allowed)
				(copperpour not_allowed)
				(footprints allowed)
			)
			(placement
				(enabled no)
				(sheetname "")
			)
			(fill
				(thermal_gap 0.5)
				(thermal_bridge_width 0.5)
				(island_removal_mode 0)
			)
			(polygon
				(pts
					(arc
						(start 77.999844 -218.10091)
						(mid 86.000844 -210.09991)
						(end 77.999844 -202.09891)
					)
					(arc
						(start 77.999844 -202.09891)
						(mid 76.564744 -203.53401)
						(end 77.999844 -204.96911)
					)
					(arc
						(start 77.999844 -204.96911)
						(mid 83.130644 -210.09991)
						(end 77.999844 -215.23071)
					)
					(arc
						(start 77.999844 -215.23071)
						(mid 76.564744 -216.66581)
						(end 77.999844 -218.10091)
					)
				)
			)
		)
		(zone
			(layers "F.Cu" "B.Cu" "In1.Cu" "In2.Cu" "In3.Cu" "In4.Cu" "In5.Cu" "In6.Cu")
			(hatch none 0.5)
			(connect_pads
				(clearance 0)
			)
			(min_thickness 0.25)
			(keepout
				(tracks not_allowed)
				(vias allowed)
				(pads allowed)
				(copperpour not_allowed)
				(footprints allowed)
			)
			(placement
				(enabled no)
				(sheetname "")
			)
			(fill
				(thermal_gap 0.5)
				(thermal_bridge_width 0.5)
				(island_removal_mode 0)
			)
			(polygon
				(pts
					(arc
						(start 80.511904 -210.09991)
						(mid 75.487784 -210.09991)
						(end 80.511904 -210.09991)
					)
				)
			)
		)
	)
	(footprint ""
		(layer "F.Cu")
		(at 46.436788 -251.703332 180)
		(property "Reference" "R100"
			(at 2.469388 -1.292098 0)
			(unlocked yes)
			(layer "F.SilkS")
			(effects
				(font
					(size 0.7874 0.5842)
					(thickness 0.1524)
				)
				(justify left)
			)
		)
		(property "Value" ""
			(at 0 0 180)
			(layer "F.Fab")
			(effects
				(font
					(size 1.27 1.27)
				)
			)
		)
		(duplicate_pad_numbers_are_jumpers no)
		(fp_line
			(start 0.7874 0.4064)
			(end -0.7874 0.4064)
			(stroke
				(width 0.1524)
				(type default)
			)
			(layer "F.SilkS")
		)
		(fp_line
			(start 0.7874 -0.4064)
			(end 0.7874 0.4064)
			(stroke
				(width 0.1524)
				(type default)
			)
			(layer "F.SilkS")
		)
		(fp_line
			(start -0.7874 0.4064)
			(end -0.7874 -0.4064)
			(stroke
				(width 0.1524)
				(type default)
			)
			(layer "F.SilkS")
		)
		(fp_line
			(start -0.7874 -0.4064)
			(end 0.7874 -0.4064)
			(stroke
				(width 0.1524)
				(type default)
			)
			(layer "F.SilkS")
		)
		(fp_poly
			(pts
				(xy -0.508 0.2794) (xy -0.508 0.2286) (xy -0.635 0.2286) (xy -0.635 -0.254) (xy -0.5334 -0.254)
				(xy -0.5334 -0.2794) (xy 0.5334 -0.2794) (xy 0.5334 -0.254) (xy 0.635 -0.254) (xy 0.635 0.254) (xy 0.5334 0.254)
				(xy 0.5334 0.2794)
			)
			(stroke
				(width 0)
				(type default)
			)
			(fill no)
			(layer "F.CrtYd")
		)
		(pad "1" smd rect
			(at 0.40005 0 180)
			(size 0.4572 0.508)
			(layers "F.Cu" "F.Mask" "F.Paste")
			(net "PSU6_REMOTE_R_P")
		)
		(pad "2" smd rect
			(at -0.40005 0 180)
			(size 0.4572 0.508)
			(layers "F.Cu" "F.Mask" "F.Paste")
			(net "P12V")
		)
	)
	(footprint ""
		(layer "F.Cu")
		(at 39.798752 -197.274942)
		(property "Reference" "R42"
			(at 2.029968 0.33401 0)
			(unlocked yes)
			(layer "F.SilkS")
			(effects
				(font
					(size 0.7874 0.5842)
					(thickness 0.1524)
				)
				(justify left)
			)
		)
		(property "Value" ""
			(at 0 0 0)
			(layer "F.Fab")
			(effects
				(font
					(size 1.27 1.27)
				)
			)
		)
		(duplicate_pad_numbers_are_jumpers no)
		(fp_line
			(start -0.7874 -0.4064)
			(end 0.7874 -0.4064)
			(stroke
				(width 0.1524)
				(type default)
			)
			(layer "F.SilkS")
		)
		(fp_line
			(start -0.7874 0.4064)
			(end -0.7874 -0.4064)
			(stroke
				(width 0.1524)
				(type default)
			)
			(layer "F.SilkS")
		)
		(fp_line
			(start 0.7874 -0.4064)
			(end 0.7874 0.4064)
			(stroke
				(width 0.1524)
				(type default)
			)
			(layer "F.SilkS")
		)
		(fp_line
			(start 0.7874 0.4064)
			(end -0.7874 0.4064)
			(stroke
				(width 0.1524)
				(type default)
			)
			(layer "F.SilkS")
		)
		(fp_poly
			(pts
				(xy -0.508 0.2794) (xy -0.508 0.2286) (xy -0.635 0.2286) (xy -0.635 -0.254) (xy -0.5334 -0.254)
				(xy -0.5334 -0.2794) (xy 0.5334 -0.2794) (xy 0.5334 -0.254) (xy 0.635 -0.254) (xy 0.635 0.254) (xy 0.5334 0.254)
				(xy 0.5334 0.2794)
			)
			(stroke
				(width 0)
				(type default)
			)
			(fill no)
			(layer "F.CrtYd")
		)
		(pad "1" smd rect
			(at 0.40005 0)
			(size 0.4572 0.508)
			(layers "F.Cu" "F.Mask" "F.Paste")
			(net "GND")
		)
		(pad "2" smd rect
			(at -0.40005 0)
			(size 0.4572 0.508)
			(layers "F.Cu" "F.Mask" "F.Paste")
			(net "P12V_STBY")
		)
	)
	(footprint ""
		(layer "F.Cu")
		(at 71.390764 -460.240634 -90)
		(property "Reference" "C71"
			(at -3.534156 -0.42799 90)
			(unlocked yes)
			(layer "F.SilkS")
			(effects
				(font
					(size 0.7874 0.5842)
					(thickness 0.1524)
				)
			)
		)
		(property "Value" ""
			(at 0 0 270)
			(layer "F.Fab")
			(effects
				(font
					(size 1.27 1.27)
				)
			)
		)
		(duplicate_pad_numbers_are_jumpers no)
		(fp_line
			(start -1.2954 0.5842)
			(end -1.2954 -0.5842)
			(stroke
				(width 0.1524)
				(type default)
			)
			(layer "F.SilkS")
		)
		(fp_line
			(start 1.2954 0.5842)
			(end -1.2954 0.5842)
			(stroke
				(width 0.1524)
				(type default)
			)
			(layer "F.SilkS")
		)
		(fp_line
			(start -1.2954 -0.5842)
			(end 1.2954 -0.5842)
			(stroke
				(width 0.1524)
				(type default)
			)
			(layer "F.SilkS")
		)
		(fp_line
			(start 0 -0.5842)
			(end 0 0.5842)
			(stroke
				(width 0.1524)
				(type default)
			)
			(layer "F.SilkS")
		)
		(fp_line
			(start 1.2954 -0.5842)
			(end 1.2954 0.5842)
			(stroke
				(width 0.1524)
				(type default)
			)
			(layer "F.SilkS")
		)
		(fp_poly
			(pts
				(xy 0.8636 -0.4572) (xy 0.8636 -0.3556) (xy 1.143 -0.3556) (xy 1.143 0.3556) (xy 0.8636 0.3556)
				(xy 0.8636 0.4572) (xy -0.8636 0.4572) (xy -0.8636 0.3556) (xy -1.143 0.3556) (xy -1.143 -0.3556)
				(xy -0.8636 -0.3556) (xy -0.8636 -0.4572)
			)
			(stroke
				(width 0)
				(type default)
			)
			(fill no)
			(layer "F.CrtYd")
		)
		(fp_line
			(start -0.884936 0.504952)
			(end -0.884936 -0.504952)
			(stroke
				(width 0.1)
				(type default)
			)
			(layer "F.Fab")
		)
		(fp_line
			(start 0.884936 0.504952)
			(end -0.884936 0.504952)
			(stroke
				(width 0.1)
				(type default)
			)
			(layer "F.Fab")
		)
		(fp_line
			(start -0.884936 -0.504952)
			(end 0.884936 -0.504952)
			(stroke
				(width 0.1)
				(type default)
			)
			(layer "F.Fab")
		)
		(fp_line
			(start 0.884936 -0.504952)
			(end 0.884936 0.504952)
			(stroke
				(width 0.1)
				(type default)
			)
			(layer "F.Fab")
		)
		(pad "1" smd rect
			(at 0.7366 0)
			(size 0.7112 0.8128)
			(layers "F.Cu" "F.Mask" "F.Paste")
			(net "P12V")
		)
		(pad "2" smd rect
			(at -0.7366 0)
			(size 0.7112 0.8128)
			(layers "F.Cu" "F.Mask" "F.Paste")
			(net "GND")
		)
	)
	(footprint ""
		(layer "F.Cu")
		(at 39.858442 -110.774226 180)
		(property "Reference" "R3"
			(at -1.626616 0.658622 0)
			(unlocked yes)
			(layer "F.SilkS")
			(effects
				(font
					(size 0.7874 0.5842)
					(thickness 0.1524)
				)
				(justify left)
			)
		)
		(property "Value" ""
			(at 0 0 180)
			(layer "F.Fab")
			(effects
				(font
					(size 1.27 1.27)
				)
			)
		)
		(duplicate_pad_numbers_are_jumpers no)
		(fp_line
			(start 0.7874 0.4064)
			(end -0.7874 0.4064)
			(stroke
				(width 0.1524)
				(type default)
			)
			(layer "F.SilkS")
		)
		(fp_line
			(start 0.7874 -0.4064)
			(end 0.7874 0.4064)
			(stroke
				(width 0.1524)
				(type default)
			)
			(layer "F.SilkS")
		)
		(fp_line
			(start -0.7874 0.4064)
			(end -0.7874 -0.4064)
			(stroke
				(width 0.1524)
				(type default)
			)
			(layer "F.SilkS")
		)
		(fp_line
			(start -0.7874 -0.4064)
			(end 0.7874 -0.4064)
			(stroke
				(width 0.1524)
				(type default)
			)
			(layer "F.SilkS")
		)
		(fp_poly
			(pts
				(xy -0.508 0.2794) (xy -0.508 0.2286) (xy -0.635 0.2286) (xy -0.635 -0.254) (xy -0.5334 -0.254)
				(xy -0.5334 -0.2794) (xy 0.5334 -0.2794) (xy 0.5334 -0.254) (xy 0.635 -0.254) (xy 0.635 0.254) (xy 0.5334 0.254)
				(xy 0.5334 0.2794)
			)
			(stroke
				(width 0)
				(type default)
			)
			(fill no)
			(layer "F.CrtYd")
		)
		(pad "1" smd rect
			(at 0.40005 0 180)
			(size 0.4572 0.508)
			(layers "F.Cu" "F.Mask" "F.Paste")
			(net "PSU2_REMOTE_P")
		)
		(pad "2" smd rect
			(at -0.40005 0 180)
			(size 0.4572 0.508)
			(layers "F.Cu" "F.Mask" "F.Paste")
			(net "P12V")
		)
	)
	(footprint ""
		(layer "F.Cu")
		(at 46.40834 -243.096034 180)
		(property "Reference" "R92"
			(at 4.252722 -0.212598 0)
			(unlocked yes)
			(layer "F.SilkS")
			(effects
				(font
					(size 0.7874 0.5842)
					(thickness 0.1524)
				)
				(justify left)
			)
		)
		(property "Value" ""
			(at 0 0 180)
			(layer "F.Fab")
			(effects
				(font
					(size 1.27 1.27)
				)
			)
		)
		(duplicate_pad_numbers_are_jumpers no)
		(fp_line
			(start 0.7874 0.4064)
			(end -0.7874 0.4064)
			(stroke
				(width 0.1524)
				(type default)
			)
			(layer "F.SilkS")
		)
		(fp_line
			(start 0.7874 -0.4064)
			(end 0.7874 0.4064)
			(stroke
				(width 0.1524)
				(type default)
			)
			(layer "F.SilkS")
		)
		(fp_line
			(start -0.7874 0.4064)
			(end -0.7874 -0.4064)
			(stroke
				(width 0.1524)
				(type default)
			)
			(layer "F.SilkS")
		)
		(fp_line
			(start -0.7874 -0.4064)
			(end 0.7874 -0.4064)
			(stroke
				(width 0.1524)
				(type default)
			)
			(layer "F.SilkS")
		)
		(fp_poly
			(pts
				(xy -0.508 0.2794) (xy -0.508 0.2286) (xy -0.635 0.2286) (xy -0.635 -0.254) (xy -0.5334 -0.254)
				(xy -0.5334 -0.2794) (xy 0.5334 -0.2794) (xy 0.5334 -0.254) (xy 0.635 -0.254) (xy 0.635 0.254) (xy 0.5334 0.254)
				(xy 0.5334 0.2794)
			)
			(stroke
				(width 0)
				(type default)
			)
			(fill no)
			(layer "F.CrtYd")
		)
		(pad "1" smd rect
			(at 0.40005 0 180)
			(size 0.4572 0.508)
			(layers "F.Cu" "F.Mask" "F.Paste")
			(net "PSU2_REMOTE_R_P")
		)
		(pad "2" smd rect
			(at -0.40005 0 180)
			(size 0.4572 0.508)
			(layers "F.Cu" "F.Mask" "F.Paste")
			(net "P12V")
		)
	)
)
